(kicad_pcb
	(version 20260206)
	(generator "pcbnew")
	(generator_version "10.0")
	(general
		(thickness 1.6)
		(legacy_teardrops no)
	)
	(paper "A4")
	(title_block
		(title "Wiwynn_Tioga_Pass_MB.brd")
		(comment 1 "Tioga Pass / footprints 309-312 of 4770")
	)
	(layers
		(0 "F.Cu" signal "TOP")
		(4 "In1.Cu" signal "L2GND")
		(6 "In2.Cu" signal "L3")
		(8 "In3.Cu" signal "L4GND")
		(10 "In4.Cu" signal "L5")
		(12 "In5.Cu" signal "L6GND")
		(14 "In6.Cu" signal "L7VCC")
		(16 "In7.Cu" signal "L8VCC")
		(18 "In8.Cu" signal "L9GND")
		(20 "In9.Cu" signal "L10")
		(22 "In10.Cu" signal "L11GND")
		(24 "In11.Cu" signal "L12")
		(26 "In12.Cu" signal "L13GND")
		(2 "B.Cu" signal "BOTTOM")
		(9 "F.Adhes" user "F.Adhesive")
		(11 "B.Adhes" user "B.Adhesive")
		(13 "F.Paste" user "Package Geometry/Pastemask Top")
		(15 "B.Paste" user "Package Geometry/Pastemask Bottom")
		(5 "F.SilkS" user "Ref Des/Silkscreen Top")
		(7 "B.SilkS" user "Ref Des/Silkscreen Bottom")
		(1 "F.Mask" user "Board Geometry/Soldermask Top")
		(3 "B.Mask" user "Board Geometry/Soldermask Bottom")
		(17 "Dwgs.User" user "User.Drawings")
		(19 "Cmts.User" user "User.Comments")
		(21 "Eco1.User" user "User.Eco1")
		(23 "Eco2.User" user "User.Eco2")
		(25 "Edge.Cuts" user "Board Geometry/Outline")
		(27 "Margin" user)
		(31 "F.CrtYd" user "Package Geometry/Place Bound Top")
		(29 "B.CrtYd" user "Package Geometry/Place Bound Bottom")
		(35 "F.Fab" user "Ref Des/Assembly Top")
		(33 "B.Fab" user "Ref Des/Assembly Bottom")
	)
	(footprint ""
		(layer "F.Cu")
		(at 32.289496 -61.095382 -90)
		(property "Reference" "C1E24"
			(at 0 0 270)
			(layer "F.SilkS")
			(hide yes)
			(effects
				(font
					(size 1.27 1.27)
				)
			)
		)
		(property "Value" ""
			(at 0 0 270)
			(layer "F.Fab")
			(effects
				(font
					(size 1.27 1.27)
				)
			)
		)
		(duplicate_pad_numbers_are_jumpers no)
		(fp_rect
			(start 0.3048 0.9906)
			(end -0.3048 -0.1016)
			(stroke
				(width 0)
				(type default)
			)
			(fill no)
			(layer "F.CrtYd")
		)
		(fp_line
			(start -0.3048 0.9906)
			(end 0.3048 0.9906)
			(stroke
				(width 0.1)
				(type default)
			)
			(layer "F.Fab")
		)
		(fp_line
			(start 0.3048 0.9906)
			(end 0.3048 -0.1016)
			(stroke
				(width 0.1)
				(type default)
			)
			(layer "F.Fab")
		)
		(fp_line
			(start -0.3048 -0.1016)
			(end -0.3048 0.9906)
			(stroke
				(width 0.1)
				(type default)
			)
			(layer "F.Fab")
		)
		(fp_line
			(start 0.3048 -0.1016)
			(end -0.3048 -0.1016)
			(stroke
				(width 0.1)
				(type default)
			)
			(layer "F.Fab")
		)
		(pad "1" smd rect
			(at 0 0 270)
			(size 0.508 0.508)
			(layers "F.Cu" "F.Mask" "F.Paste")
			(net "VR_PVCCIN_CPU1_PH2_VCIN")
		)
		(pad "2" smd rect
			(at 0 0.889 270)
			(size 0.508 0.508)
			(layers "F.Cu" "F.Mask" "F.Paste")
			(net "GND")
		)
		(zone
			(layer "F.Cu")
			(hatch none 0.5)
			(connect_pads
				(clearance 0)
			)
			(min_thickness 0.25)
			(keepout
				(tracks not_allowed)
				(vias allowed)
				(pads allowed)
				(copperpour not_allowed)
				(footprints allowed)
			)
			(placement
				(enabled no)
				(sheetname "")
			)
			(fill
				(thermal_gap 0.5)
				(thermal_bridge_width 0.5)
				(island_removal_mode 0)
			)
			(polygon
				(pts
					(xy 31.654496 -60.841382) (xy 32.035496 -60.841382) (xy 32.035496 -61.349382) (xy 31.654496 -61.349382)
				)
			)
		)
		(zone
			(layer "F.Cu")
			(hatch none 0.5)
			(connect_pads
				(clearance 0)
			)
			(min_thickness 0.25)
			(keepout
				(tracks allowed)
				(vias not_allowed)
				(pads allowed)
				(copperpour not_allowed)
				(footprints allowed)
			)
			(placement
				(enabled no)
				(sheetname "")
			)
			(fill
				(thermal_gap 0.5)
				(thermal_bridge_width 0.5)
				(island_removal_mode 0)
			)
			(polygon
				(pts
					(xy 31.654496 -60.841382) (xy 32.035496 -60.841382) (xy 32.035496 -61.349382) (xy 31.654496 -61.349382)
				)
			)
		)
	)
	(footprint ""
		(layer "F.Cu")
		(at 185.928 -100.838 90)
		(property "Reference" "L4C1"
			(at 0 0 90)
			(layer "F.SilkS")
			(hide yes)
			(effects
				(font
					(size 1.27 1.27)
				)
			)
		)
		(property "Value" "*"
			(at 4.9784 -0.6477 90)
			(unlocked yes)
			(layer "F.Fab")
			(hide yes)
			(effects
				(font
					(size 1.27 1.016)
					(thickness 0.1524)
				)
			)
		)
		(property "Device Type" "IND-80NH-1-GP_DISCRET-GC2-IND-A"
			(at 4.9784 -2.1717 90)
			(unlocked yes)
			(layer "F.Fab")
			(hide yes)
			(effects
				(font
					(size 1.27 1.016)
					(thickness 0.1524)
				)
			)
		)
		(duplicate_pad_numbers_are_jumpers no)
		(fp_line
			(start 2.8575 -3.4544)
			(end 2.8575 3.4544)
			(stroke
				(width 0.1524)
				(type default)
			)
			(layer "F.SilkS")
		)
		(fp_line
			(start -2.8575 -3.4544)
			(end 2.8575 -3.4544)
			(stroke
				(width 0.1524)
				(type default)
			)
			(layer "F.SilkS")
		)
		(fp_line
			(start 2.8575 3.4544)
			(end -2.8575 3.4544)
			(stroke
				(width 0.1524)
				(type default)
			)
			(layer "F.SilkS")
		)
		(fp_line
			(start -2.8575 3.4544)
			(end -2.8575 -3.4544)
			(stroke
				(width 0.1524)
				(type default)
			)
			(layer "F.SilkS")
		)
		(fp_rect
			(start -2.6035 2.6035)
			(end 2.6035 -2.6035)
			(stroke
				(width 0)
				(type default)
			)
			(fill no)
			(layer "F.CrtYd")
		)
		(fp_poly
			(pts
				(xy -3.1115 3.5306) (xy -3.1115 2.6035) (xy 2.6035 2.6035) (xy 2.6035 -2.6035) (xy -2.6035 -2.6035)
				(xy -2.6035 2.5908) (xy -3.1115 2.5908) (xy -3.1115 -3.5306) (xy 3.1115 -3.5306) (xy 3.1115 3.5306)
			)
			(stroke
				(width 0)
				(type default)
			)
			(fill no)
			(layer "F.CrtYd")
		)
		(fp_rect
			(start -3.1115 3.5306)
			(end 3.1115 -3.5306)
			(stroke
				(width 0)
				(type default)
			)
			(fill no)
			(layer "F.Fab")
		)
		(pad "1" smd rect
			(at 0 -2.395982 90)
			(size 2.2606 1.6002)
			(layers "F.Cu" "F.Mask" "F.Paste")
			(net "P12V_STBY")
		)
		(pad "2" smd rect
			(at 0 2.395982 90)
			(size 2.2606 1.6002)
			(layers "F.Cu" "F.Mask" "F.Paste")
			(net "VR_FET_SW_P12V_STBY_PVCCIN_CPU0")
		)
	)
	(footprint ""
		(layer "F.Cu")
		(at 275.909024 -77.429614)
		(property "Reference" "C5D38"
			(at 0 0 0)
			(layer "F.SilkS")
			(hide yes)
			(effects
				(font
					(size 1.27 1.27)
				)
			)
		)
		(property "Value" ""
			(at 0 0 0)
			(layer "F.Fab")
			(effects
				(font
					(size 1.27 1.27)
				)
			)
		)
		(duplicate_pad_numbers_are_jumpers no)
		(fp_poly
			(pts
				(xy -0.4953 -0.2032) (xy 0.4953 -0.2032) (xy 0.4953 1.6002) (xy -0.4953 1.6002)
			)
			(stroke
				(width 0)
				(type default)
			)
			(fill no)
			(layer "F.CrtYd")
		)
		(fp_line
			(start -0.4953 -0.2032)
			(end 0.4953 -0.2032)
			(stroke
				(width 0.1)
				(type default)
			)
			(layer "F.Fab")
		)
		(fp_line
			(start -0.4953 1.6002)
			(end -0.4953 -0.2032)
			(stroke
				(width 0.1)
				(type default)
			)
			(layer "F.Fab")
		)
		(fp_line
			(start 0.4953 -0.2032)
			(end 0.4953 1.6002)
			(stroke
				(width 0.1)
				(type default)
			)
			(layer "F.Fab")
		)
		(fp_line
			(start 0.4953 1.6002)
			(end -0.4953 1.6002)
			(stroke
				(width 0.1)
				(type default)
			)
			(layer "F.Fab")
		)
		(pad "1" smd rect
			(at 0 0)
			(size 0.762 0.889)
			(layers "F.Cu" "F.Mask" "F.Paste")
			(net "PVCCMCP_CPU0")
		)
		(pad "2" smd rect
			(at 0 1.397)
			(size 0.762 0.889)
			(layers "F.Cu" "F.Mask" "F.Paste")
			(net "GND")
		)
		(zone
			(layer "F.Cu")
			(hatch none 0.5)
			(connect_pads
				(clearance 0)
			)
			(min_thickness 0.25)
			(keepout
				(tracks not_allowed)
				(vias allowed)
				(pads allowed)
				(copperpour not_allowed)
				(footprints allowed)
			)
			(placement
				(enabled no)
				(sheetname "")
			)
			(fill
				(thermal_gap 0.5)
				(thermal_bridge_width 0.5)
				(island_removal_mode 0)
			)
			(polygon
				(pts
					(xy 275.528024 -76.985114) (xy 276.290024 -76.985114) (xy 276.290024 -76.477114) (xy 275.528024 -76.477114)
				)
			)
		)
	)
	(footprint ""
		(layer "F.Cu")
		(at 49.4284 -93.7514)
		(property "Reference" "C1C19"
			(at 0 0 0)
			(layer "F.SilkS")
			(hide yes)
			(effects
				(font
					(size 1.27 1.27)
				)
			)
		)
		(property "Value" ""
			(at 0 0 0)
			(layer "F.Fab")
			(effects
				(font
					(size 1.27 1.27)
				)
			)
		)
		(duplicate_pad_numbers_are_jumpers no)
		(fp_poly
			(pts
				(xy -0.4953 -0.2032) (xy 0.4953 -0.2032) (xy 0.4953 1.6002) (xy -0.4953 1.6002)
			)
			(stroke
				(width 0)
				(type default)
			)
			(fill no)
			(layer "F.CrtYd")
		)
		(fp_line
			(start -0.4953 -0.2032)
			(end 0.4953 -0.2032)
			(stroke
				(width 0.1)
				(type default)
			)
			(layer "F.Fab")
		)
		(fp_line
			(start -0.4953 1.6002)
			(end -0.4953 -0.2032)
			(stroke
				(width 0.1)
				(type default)
			)
			(layer "F.Fab")
		)
		(fp_line
			(start 0.4953 -0.2032)
			(end 0.4953 1.6002)
			(stroke
				(width 0.1)
				(type default)
			)
			(layer "F.Fab")
		)
		(fp_line
			(start 0.4953 1.6002)
			(end -0.4953 1.6002)
			(stroke
				(width 0.1)
				(type default)
			)
			(layer "F.Fab")
		)
		(pad "1" smd rect
			(at 0 0)
			(size 0.762 0.889)
			(layers "F.Cu" "F.Mask" "F.Paste")
			(net "PVSA_CPU1")
		)
		(pad "2" smd rect
			(at 0 1.397)
			(size 0.762 0.889)
			(layers "F.Cu" "F.Mask" "F.Paste")
			(net "GND")
		)
		(zone
			(layer "F.Cu")
			(hatch none 0.5)
			(connect_pads
				(clearance 0)
			)
			(min_thickness 0.25)
			(keepout
				(tracks not_allowed)
				(vias allowed)
				(pads allowed)
				(copperpour not_allowed)
				(footprints allowed)
			)
			(placement
				(enabled no)
				(sheetname "")
			)
			(fill
				(thermal_gap 0.5)
				(thermal_bridge_width 0.5)
				(island_removal_mode 0)
			)
			(polygon
				(pts
					(xy 49.0474 -93.3069) (xy 49.8094 -93.3069) (xy 49.8094 -92.7989) (xy 49.0474 -92.7989)
				)
			)
		)
	)
)
